# TIMECARD (Time Appliance Project (Time Card)) — schematic netlist excerpt (pin names and nets, part order shuffled) for the footprints in the layout excerpt that follows; sources: Cadence DE-HDL packaged netlist, KiCad conversion of R4006-B0001-02_R01.brd

C92  CAPACITOR  0.1UF 25V 10%  pkg SMC_0402R_H022  page 24 : \1\ = XP3R3V_FPGA ; \2\ = SG
R245  RESISTOR  0OHM -  pkg SMC_0402R_H016  page 29 : \1\ = XP1R0V_FPGA_PG ; \2\ = XP1R0V_PG

(kicad_pcb
	(version 20260206)
	(generator "pcbnew")
	(generator_version "10.0")
	(general
		(thickness 1.6)
		(legacy_teardrops no)
	)
	(paper "A4")
	(title_block
		(title "timecard-production-celestica-r4006 — R4006-B0001-02_R01.brd")
		(comment 1 "Time Appliance Project (Time Card) / footprints 645-646 of 1113")
	)
	(layers
		(0 "F.Cu" signal "TOP")
		(4 "In1.Cu" signal "L02_GND1")
		(6 "In2.Cu" signal "L03_SIG1")
		(8 "In3.Cu" signal "L04_GND2")
		(10 "In4.Cu" signal "L05_VCC1")
		(12 "In5.Cu" signal "L06_VCC2")
		(14 "In6.Cu" signal "L07_GND3")
		(16 "In7.Cu" signal "L08_SIG2")
		(18 "In8.Cu" signal "L09_GND4")
		(2 "B.Cu" signal "BOTTOM")
		(9 "F.Adhes" user "F.Adhesive")
		(11 "B.Adhes" user "B.Adhesive")
		(13 "F.Paste" user "Package Geometry/Pastemask Top")
		(15 "B.Paste" user "Package Geometry/Pastemask Bottom")
		(5 "F.SilkS" user "Ref Des/Silkscreen Top")
		(7 "B.SilkS" user "Ref Des/Silkscreen Bottom")
		(1 "F.Mask" user "Board Geometry/Soldermask Top")
		(3 "B.Mask" user "Board Geometry/Soldermask Bottom")
		(17 "Dwgs.User" user "User.Drawings")
		(19 "Cmts.User" user "User.Comments")
		(21 "Eco1.User" user "User.Eco1")
		(23 "Eco2.User" user "User.Eco2")
		(25 "Edge.Cuts" user "Board Geometry/Outline")
		(27 "Margin" user)
		(31 "F.CrtYd" user "Package Geometry/Place Bound Top")
		(29 "B.CrtYd" user "Package Geometry/Place Bound Bottom")
		(35 "F.Fab" user "Ref Des/Assembly Top")
		(33 "B.Fab" user "Ref Des/Assembly Bottom")
	)
	(footprint ""
		(layer "F.Cu")
		(at 138.811 -59.563 -90)
		(property "Reference" "R245"
			(at -3.048 1.48463 90)
			(unlocked yes)
			(layer "F.SilkS")
			(effects
				(font
					(size 0.7874 0.5842)
					(thickness 0.1524)
				)
			)
		)
		(property "Value" "VAL*"
			(at 0.02032 2.13233 270)
			(unlocked yes)
			(layer "F.Fab")
			(hide yes)
			(effects
				(font
					(size 0.7874 0.5842)
					(thickness 0.1524)
				)
			)
		)
		(property "Device Type" "RESISTOR-G155-100R0-J0,0OHM,-"
			(at 0.008382 1.210564 270)
			(unlocked yes)
			(layer "F.Fab")
			(hide yes)
			(effects
				(font
					(size 0.7874 0.5842)
					(thickness 0.1524)
				)
			)
		)
		(property "User Part Number" "PARTNUM*"
			(at 0.02032 4.024884 270)
			(unlocked yes)
			(layer "Cmts.User")
			(hide yes)
			(effects
				(font
					(size 0.7874 0.5842)
					(thickness 0.1524)
				)
			)
		)
		(property "Tolerance" "TOL*"
			(at 0.044704 3.05435 270)
			(unlocked yes)
			(layer "Cmts.User")
			(hide yes)
			(effects
				(font
					(size 0.7874 0.5842)
					(thickness 0.1524)
				)
			)
		)
		(duplicate_pad_numbers_are_jumpers no)
		(fp_line
			(start -1.143 0.5588)
			(end 1.143 0.5588)
			(stroke
				(width 0.1)
				(type default)
			)
			(layer "F.SilkS")
		)
		(fp_line
			(start 1.143 0.5588)
			(end 1.143 -0.5588)
			(stroke
				(width 0.1)
				(type default)
			)
			(layer "F.SilkS")
		)
		(fp_line
			(start -1.143 -0.5588)
			(end -1.143 0.5588)
			(stroke
				(width 0.1)
				(type default)
			)
			(layer "F.SilkS")
		)
		(fp_line
			(start 1.143 -0.5588)
			(end -1.143 -0.5588)
			(stroke
				(width 0.1)
				(type default)
			)
			(layer "F.SilkS")
		)
		(fp_rect
			(start 1.143 0.5588)
			(end -1.143 -0.5588)
			(stroke
				(width 0)
				(type default)
			)
			(fill no)
			(layer "F.CrtYd")
		)
		(fp_line
			(start -0.508 0.3048)
			(end 0.508 0.3048)
			(stroke
				(width 0.1)
				(type default)
			)
			(layer "F.Fab")
		)
		(fp_line
			(start 0.508 0.3048)
			(end 0.508 -0.3048)
			(stroke
				(width 0.1)
				(type default)
			)
			(layer "F.Fab")
		)
		(fp_line
			(start -0.508 -0.3048)
			(end -0.508 0.3048)
			(stroke
				(width 0.1)
				(type default)
			)
			(layer "F.Fab")
		)
		(fp_line
			(start 0.508 -0.3048)
			(end -0.508 -0.3048)
			(stroke
				(width 0.1)
				(type default)
			)
			(layer "F.Fab")
		)
		(pad "1" smd rect
			(at -0.5334 0 270)
			(size 0.7112 0.6096)
			(layers "F.Cu" "F.Mask" "F.Paste")
			(net "XP1R0V_FPGA_PG")
		)
		(pad "2" smd rect
			(at 0.5334 0 270)
			(size 0.7112 0.6096)
			(layers "F.Cu" "F.Mask" "F.Paste")
			(net "XP1R0V_PG")
		)
		(zone
			(layer "F.Cu")
			(hatch none 0.5)
			(connect_pads
				(clearance 0)
			)
			(min_thickness 0.25)
			(keepout
				(tracks allowed)
				(vias not_allowed)
				(pads allowed)
				(copperpour not_allowed)
				(footprints allowed)
			)
			(placement
				(enabled no)
				(sheetname "")
			)
			(fill
				(thermal_gap 0.5)
				(thermal_bridge_width 0.5)
				(island_removal_mode 0)
			)
			(polygon
				(pts
					(xy 138.5062 -59.4868) (xy 139.1158 -59.4868) (xy 139.1158 -59.6392) (xy 138.5062 -59.6392)
				)
			)
		)
	)
	(footprint ""
		(layer "F.Cu")
		(at 133.858 -23.368)
		(property "Reference" "C92"
			(at -0.635 -4.78663 0)
			(unlocked yes)
			(layer "F.SilkS")
			(effects
				(font
					(size 0.7874 0.5842)
					(thickness 0.1524)
				)
			)
		)
		(property "Value" "VAL*"
			(at 0.0762 2.067306 0)
			(unlocked yes)
			(layer "F.Fab")
			(hide yes)
			(effects
				(font
					(size 0.7874 0.5842)
					(thickness 0.1524)
				)
			)
		)
		(property "Device Type" "CAPACITOR-G105-0B104-EK,0.1UF,A"
			(at 0.0508 1.127506 0)
			(unlocked yes)
			(layer "F.Fab")
			(hide yes)
			(effects
				(font
					(size 0.7874 0.5842)
					(thickness 0.1524)
				)
			)
		)
		(property "User Part Number" "PARTNUM*"
			(at 0.1016 4.023106 0)
			(unlocked yes)
			(layer "Cmts.User")
			(hide yes)
			(effects
				(font
					(size 0.7874 0.5842)
					(thickness 0.1524)
				)
			)
		)
		(property "Tolerance" "TOL*"
			(at 0.0762 3.032506 0)
			(unlocked yes)
			(layer "Cmts.User")
			(hide yes)
			(effects
				(font
					(size 0.7874 0.5842)
					(thickness 0.1524)
				)
			)
		)
		(duplicate_pad_numbers_are_jumpers no)
		(fp_line
			(start -1.143 -0.5588)
			(end -1.143 0.5588)
			(stroke
				(width 0.1)
				(type default)
			)
			(layer "F.SilkS")
		)
		(fp_line
			(start -1.143 0.5588)
			(end 1.143 0.5588)
			(stroke
				(width 0.1)
				(type default)
			)
			(layer "F.SilkS")
		)
		(fp_line
			(start 1.143 -0.5588)
			(end -1.143 -0.5588)
			(stroke
				(width 0.1)
				(type default)
			)
			(layer "F.SilkS")
		)
		(fp_line
			(start 1.143 0.5588)
			(end 1.143 -0.5588)
			(stroke
				(width 0.1)
				(type default)
			)
			(layer "F.SilkS")
		)
		(fp_rect
			(start 1.143 -0.5588)
			(end -1.143 0.5588)
			(stroke
				(width 0)
				(type default)
			)
			(fill no)
			(layer "F.CrtYd")
		)
		(fp_line
			(start -0.508 -0.3048)
			(end -0.508 0.3048)
			(stroke
				(width 0.1)
				(type default)
			)
			(layer "F.Fab")
		)
		(fp_line
			(start -0.508 0.3048)
			(end 0.508 0.3048)
			(stroke
				(width 0.1)
				(type default)
			)
			(layer "F.Fab")
		)
		(fp_line
			(start 0.508 -0.3048)
			(end -0.508 -0.3048)
			(stroke
				(width 0.1)
				(type default)
			)
			(layer "F.Fab")
		)
		(fp_line
			(start 0.508 0.3048)
			(end 0.508 -0.3048)
			(stroke
				(width 0.1)
				(type default)
			)
			(layer "F.Fab")
		)
		(pad "1" smd rect
			(at -0.5334 0)
			(size 0.7112 0.6096)
			(layers "F.Cu" "F.Mask" "F.Paste")
			(net "XP3R3V_FPGA")
		)
		(pad "2" smd rect
			(at 0.5334 0)
			(size 0.7112 0.6096)
			(layers "F.Cu" "F.Mask" "F.Paste")
			(net "SG")
		)
		(zone
			(layer "F.Cu")
			(hatch none 0.5)
			(connect_pads
				(clearance 0)
			)
			(min_thickness 0.25)
			(keepout
				(tracks allowed)
				(vias not_allowed)
				(pads allowed)
				(copperpour not_allowed)
				(footprints allowed)
			)
			(placement
				(enabled no)
				(sheetname "")
			)
			(fill
				(thermal_gap 0.5)
				(thermal_bridge_width 0.5)
				(island_removal_mode 0)
			)
			(polygon
				(pts
					(xy 133.9342 -23.6728) (xy 133.7818 -23.6728) (xy 133.7818 -23.0632) (xy 133.9342 -23.0632)
				)
			)
		)
	)
)
